# T6G (Grand Teton) — schematic netlist excerpt (pin names and nets, part order shuffled) for the footprints in the layout excerpt that follows; sources: Cadence DE-HDL packaged netlist, KiCad conversion of 04192023_DAF0TMB3IC0_F0TG_MB_C_brd_V02_OCP.brd

C796  Q_CAP  10UF 6.3V 20% X6S  pkg C0402  page 301 : A = P0V9_CPU0_RT2_2A ; B = GND
R3165  Q_RES  10K 1% CHIP  pkg 0402LF  page 137 : A = GND ; B = OCP_V3_2_MAIN_PWR_EN

(kicad_pcb
	(version 20260206)
	(generator "pcbnew")
	(generator_version "10.0")
	(general
		(thickness 1.6)
		(legacy_teardrops no)
	)
	(paper "A4")
	(title_block
		(title "04192023_DAF0TMB3IC0_F0TG_MB_C_brd_V02_OCP.brd")
		(comment 1 "Grand Teton / footprints 7396-7397 of 8354")
	)
	(layers
		(0 "F.Cu" signal "TOP")
		(4 "In1.Cu" signal "GND")
		(6 "In2.Cu" signal "IN1")
		(8 "In3.Cu" signal "GND1")
		(10 "In4.Cu" signal "IN2")
		(12 "In5.Cu" signal "GND2")
		(14 "In6.Cu" signal "IN3")
		(16 "In7.Cu" signal "GND3")
		(18 "In8.Cu" signal "VCC")
		(20 "In9.Cu" signal "VCC1")
		(22 "In10.Cu" signal "GND4")
		(24 "In11.Cu" signal "IN4")
		(26 "In12.Cu" signal "GND5")
		(28 "In13.Cu" signal "IN5")
		(30 "In14.Cu" signal "GND6")
		(32 "In15.Cu" signal "IN6")
		(34 "In16.Cu" signal "GND7")
		(2 "B.Cu" signal "BOTTOM")
		(9 "F.Adhes" user "F.Adhesive")
		(11 "B.Adhes" user "B.Adhesive")
		(13 "F.Paste" user "Package Geometry/Pastemask Top")
		(15 "B.Paste" user "Package Geometry/Pastemask Bottom")
		(5 "F.SilkS" user "Ref Des/Silkscreen Top")
		(7 "B.SilkS" user "Ref Des/Silkscreen Bottom")
		(1 "F.Mask" user "Board Geometry/Soldermask Top")
		(3 "B.Mask" user "Board Geometry/Soldermask Bottom")
		(17 "Dwgs.User" user "User.Drawings")
		(19 "Cmts.User" user "User.Comments")
		(21 "Eco1.User" user "User.Eco1")
		(23 "Eco2.User" user "User.Eco2")
		(25 "Edge.Cuts" user "Board Geometry/Outline")
		(27 "Margin" user)
		(31 "F.CrtYd" user "Package Geometry/Place Bound Top")
		(29 "B.CrtYd" user "Package Geometry/Place Bound Bottom")
		(35 "F.Fab" user "Ref Des/Assembly Top")
		(33 "B.Fab" user "Ref Des/Assembly Bottom")
	)
	(footprint ""
		(layer "B.Cu")
		(at 406.618948 -398.942052 90)
		(property "Reference" "C796"
			(at 0 0 90)
			(layer "B.SilkS")
			(hide yes)
			(effects
				(font
					(size 1.27 1.27)
				)
				(justify mirror)
			)
		)
		(property "Value" ""
			(at 0 0 90)
			(layer "B.Fab")
			(effects
				(font
					(size 1.27 1.27)
				)
				(justify mirror)
			)
		)
		(duplicate_pad_numbers_are_jumpers no)
		(fp_line
			(start 0.7874 -0.4064)
			(end -0.7874 -0.4064)
			(stroke
				(width 0.1524)
				(type default)
			)
			(layer "B.SilkS")
		)
		(fp_line
			(start -0.7874 -0.4064)
			(end -0.7874 0.4064)
			(stroke
				(width 0.1524)
				(type default)
			)
			(layer "B.SilkS")
		)
		(fp_line
			(start 0.7874 0.4064)
			(end 0.7874 -0.4064)
			(stroke
				(width 0.1524)
				(type default)
			)
			(layer "B.SilkS")
		)
		(fp_line
			(start -0.7874 0.4064)
			(end 0.7874 0.4064)
			(stroke
				(width 0.1524)
				(type default)
			)
			(layer "B.SilkS")
		)
		(fp_line
			(start 0.67945 -0.305054)
			(end 0.12065 -0.305054)
			(stroke
				(width 0.1)
				(type default)
			)
			(layer "B.Fab")
		)
		(fp_line
			(start 0.12065 -0.305054)
			(end 0.12065 -0.2794)
			(stroke
				(width 0.1)
				(type default)
			)
			(layer "B.Fab")
		)
		(fp_line
			(start -0.12065 -0.3048)
			(end -0.67945 -0.3048)
			(stroke
				(width 0.1)
				(type default)
			)
			(layer "B.Fab")
		)
		(fp_line
			(start -0.67945 -0.3048)
			(end -0.67945 0.3048)
			(stroke
				(width 0.1)
				(type default)
			)
			(layer "B.Fab")
		)
		(fp_line
			(start 0.12065 -0.2794)
			(end -0.12065 -0.2794)
			(stroke
				(width 0.1)
				(type default)
			)
			(layer "B.Fab")
		)
		(fp_line
			(start -0.12065 -0.2794)
			(end -0.12065 -0.3048)
			(stroke
				(width 0.1)
				(type default)
			)
			(layer "B.Fab")
		)
		(fp_line
			(start 0.12065 0.2794)
			(end 0.12065 0.3048)
			(stroke
				(width 0.1)
				(type default)
			)
			(layer "B.Fab")
		)
		(fp_line
			(start -0.120396 0.2794)
			(end 0.12065 0.2794)
			(stroke
				(width 0.1)
				(type default)
			)
			(layer "B.Fab")
		)
		(fp_line
			(start 0.67945 0.3048)
			(end 0.67945 -0.305054)
			(stroke
				(width 0.1)
				(type default)
			)
			(layer "B.Fab")
		)
		(fp_line
			(start 0.12065 0.3048)
			(end 0.67945 0.3048)
			(stroke
				(width 0.1)
				(type default)
			)
			(layer "B.Fab")
		)
		(fp_line
			(start -0.120396 0.3048)
			(end -0.120396 0.2794)
			(stroke
				(width 0.1)
				(type default)
			)
			(layer "B.Fab")
		)
		(fp_line
			(start -0.67945 0.3048)
			(end -0.120396 0.3048)
			(stroke
				(width 0.1)
				(type default)
			)
			(layer "B.Fab")
		)
		(pad "1" smd circle
			(at 0.40005 0 270)
			(size 0 0)
			(layers "B.Cu" "B.Mask" "B.Paste")
			(net "P0V9_CPU0_RT2_2A")
		)
		(pad "2" smd circle
			(at -0.40005 0 270)
			(size 0 0)
			(layers "B.Cu" "B.Mask" "B.Paste")
			(net "GND")
		)
	)
	(footprint ""
		(layer "B.Cu")
		(at 78.159864 -11.26871 -90)
		(property "Reference" "R3165"
			(at 0 0 90)
			(layer "B.SilkS")
			(hide yes)
			(effects
				(font
					(size 1.27 1.27)
				)
				(justify mirror)
			)
		)
		(property "Value" ""
			(at 0 0 90)
			(layer "B.Fab")
			(effects
				(font
					(size 1.27 1.27)
				)
				(justify mirror)
			)
		)
		(duplicate_pad_numbers_are_jumpers no)
		(fp_line
			(start -0.7874 0.4064)
			(end 0.7874 0.4064)
			(stroke
				(width 0.1524)
				(type default)
			)
			(layer "B.SilkS")
		)
		(fp_line
			(start 0.7874 0.4064)
			(end 0.7874 -0.4064)
			(stroke
				(width 0.1524)
				(type default)
			)
			(layer "B.SilkS")
		)
		(fp_line
			(start -0.7874 -0.4064)
			(end -0.7874 0.4064)
			(stroke
				(width 0.1524)
				(type default)
			)
			(layer "B.SilkS")
		)
		(fp_line
			(start 0.7874 -0.4064)
			(end -0.7874 -0.4064)
			(stroke
				(width 0.1524)
				(type default)
			)
			(layer "B.SilkS")
		)
		(fp_line
			(start -0.67945 0.3048)
			(end -0.120396 0.3048)
			(stroke
				(width 0.1)
				(type default)
			)
			(layer "B.Fab")
		)
		(fp_line
			(start -0.120396 0.3048)
			(end -0.120396 0.2794)
			(stroke
				(width 0.1)
				(type default)
			)
			(layer "B.Fab")
		)
		(fp_line
			(start 0.12065 0.3048)
			(end 0.67945 0.3048)
			(stroke
				(width 0.1)
				(type default)
			)
			(layer "B.Fab")
		)
		(fp_line
			(start 0.67945 0.3048)
			(end 0.67945 -0.305054)
			(stroke
				(width 0.1)
				(type default)
			)
			(layer "B.Fab")
		)
		(fp_line
			(start -0.120396 0.2794)
			(end 0.12065 0.2794)
			(stroke
				(width 0.1)
				(type default)
			)
			(layer "B.Fab")
		)
		(fp_line
			(start 0.12065 0.2794)
			(end 0.12065 0.3048)
			(stroke
				(width 0.1)
				(type default)
			)
			(layer "B.Fab")
		)
		(fp_line
			(start -0.12065 -0.2794)
			(end -0.12065 -0.3048)
			(stroke
				(width 0.1)
				(type default)
			)
			(layer "B.Fab")
		)
		(fp_line
			(start 0.12065 -0.2794)
			(end -0.12065 -0.2794)
			(stroke
				(width 0.1)
				(type default)
			)
			(layer "B.Fab")
		)
		(fp_line
			(start -0.67945 -0.3048)
			(end -0.67945 0.3048)
			(stroke
				(width 0.1)
				(type default)
			)
			(layer "B.Fab")
		)
		(fp_line
			(start -0.12065 -0.3048)
			(end -0.67945 -0.3048)
			(stroke
				(width 0.1)
				(type default)
			)
			(layer "B.Fab")
		)
		(fp_line
			(start 0.12065 -0.305054)
			(end 0.12065 -0.2794)
			(stroke
				(width 0.1)
				(type default)
			)
			(layer "B.Fab")
		)
		(fp_line
			(start 0.67945 -0.305054)
			(end 0.12065 -0.305054)
			(stroke
				(width 0.1)
				(type default)
			)
			(layer "B.Fab")
		)
		(pad "1" smd circle
			(at 0.40005 0 90)
			(size 0 0)
			(layers "B.Cu" "B.Mask" "B.Paste")
			(net "GND")
		)
		(pad "2" smd circle
			(at -0.40005 0 90)
			(size 0 0)
			(layers "B.Cu" "B.Mask" "B.Paste")
			(net "OCP_V3_2_MAIN_PWR_EN")
		)
	)
)
